# S9S_MB_2U (Grand Teton) — schematic netlist excerpt (pin names and nets, part order shuffled) for the footprints in the layout excerpt that follows; sources: Cadence DE-HDL packaged netlist, KiCad conversion of 03242023_DA0F0TMBIJ0_F0T_Motherboard_J_brd_V01_OCP.brd

J8  SCONN288_ADR50017P087CC  SCONN288_ADR50017-P087CC IO  pkg DDR288S_1-1VXB  page 89
  VIN_BULK0  = P12V_S3_AUX_CPU0_NVDIMM
  RFU0  = TP_CHD_CPU0_DIMM2_FRU_0
  VIN_MGMT  = P3V3_AUX
  HSCL  = I3C_SPD_DDRABCD_CPU0_LVC1_SCL_7
  HSDA  = I3C_SPD_DDRABCD_CPU0_LVC1_SDA
  VSS0  = GND
  DQ0_A  = M_D_CPU0_SA_DQ<0>
  VSS1  = GND
  DQ1_A  = M_D_CPU0_SA_DQ<1>
  VSS2  = GND
  DQS0_A_T  = M_D_CPU0_SA_DQS_DP<0>
  DQS0_A_C  = M_D_CPU0_SA_DQS_DN<0>
  VSS3  = GND
  DQ4_A  = M_D_CPU0_SA_DQ<4>
  VSS4  = GND
  DQ5_A  = M_D_CPU0_SA_DQ<5>
  VSS5  = GND
  DQ8_A  = M_D_CPU0_SA_DQ<8>
  VSS6  = GND
  DQ9_A  = M_D_CPU0_SA_DQ<9>
  VSS7  = GND
  DQS1_A_T  = M_D_CPU0_SA_DQS_DP<1>
  DQS1_A_C  = M_D_CPU0_SA_DQS_DN<1>
  VSS8  = GND
  DQ12_A  = M_D_CPU0_SA_DQ<12>
  VSS9  = GND
  DQ13_A  = M_D_CPU0_SA_DQ<13>
  VSS10  = GND
  DQ16_A  = M_D_CPU0_SA_DQ<16>
  VSS11  = GND
  DQ17_A  = M_D_CPU0_SA_DQ<17>
  VSS12  = GND
  DQS2_A_T  = M_D_CPU0_SA_DQS_DP<2>
  DQS2_A_C  = M_D_CPU0_SA_DQS_DN<2>
  VSS13  = GND
  DQ20_A  = M_D_CPU0_SA_DQ<20>
  VSS14  = GND
  DQ21_A  = M_D_CPU0_SA_DQ<21>
  VSS15  = GND
  DQ24_A  = M_D_CPU0_SA_DQ<24>
  VSS16  = GND
  DQ25_A  = M_D_CPU0_SA_DQ<25>
  VSS17  = GND
  DQS3_A_T  = M_D_CPU0_SA_DQS_DP<3>
  DQS3_A_C  = M_D_CPU0_SA_DQS_DN<3>
  VSS18  = GND
  DQ28_A  = M_D_CPU0_SA_DQ<28>
  VSS19  = GND
  DQ29_A  = M_D_CPU0_SA_DQ<29>
  VSS20  = GND
  CB0_A  = M_D_CPU0_SA_CB<0>
  VSS21  = GND
  CB1_A  = M_D_CPU0_SA_CB<1>
  VSS22  = GND
  DQS4_A_T  = M_D_CPU0_SA_DQS_DP<4>
  DQS4_A_C  = M_D_CPU0_SA_DQS_DN<4>
  VSS23  = GND
  CB4_A  = M_D_CPU0_SA_CB<4>
  VSS24  = GND
  CB5_A  = M_D_CPU0_SA_CB<5>
  VSS25  = GND
  ALERT_N  = M_D_CPU0_ALERT_N
  VSS26  = GND
  CS0_A_N  = M_D_CPU0_SA_CS_N<2>
  VSS27  = GND
  CA0_A  = M_D_CPU0_SA_CA<0>
  VSS28  = GND
  CA2_A  = M_D_CPU0_SA_CA<2>
  VSS29  = GND
  CA4_A  = M_D_CPU0_SA_CA<4>
  VSS30  = GND
  CA6_A  = M_D_CPU0_SA_CA<6>
  VSS31  = GND
  PAR_A  = M_D_CPU0_SA_PAR
  VSS32  = GND
  CA0_B  = M_D_CPU0_SB_CA<0>
  VSS33  = GND
  CA2_B  = M_D_CPU0_SB_CA<2>
  VSS34  = GND
  CA4_B  = M_D_CPU0_SB_CA<4>
  VSS35  = GND
  CA6_B  = M_D_CPU0_SB_CA<6>
  VSS36  = GND
  CS0_B_N  = M_D_CPU0_SB_CS_N<2>
  VSS37  = GND
  \lbd||rsp_a_n\  = M_D_CPU0_SA_RSP<1>
  \lbs||rsp_b_n\  = M_D_CPU0_SB_RSP<1>
  VSS38  = GND
  CB4_B  = M_D_CPU0_SB_CB<4>
  VSS39  = GND
  CB5_B  = M_D_CPU0_SB_CB<5>
  VSS40  = GND
  \dqs9_b_t||tdqs9_b_t||dbi4_b_n\  = M_D_CPU0_SB_DQS_DP<9>
  \dqs9_b_c||tdqs9_b_c\  = M_D_CPU0_SB_DQS_DN<9>
  VSS41  = GND
  CB0_B  = M_D_CPU0_SB_CB<0>
  VSS42  = GND
  CB1_B  = M_D_CPU0_SB_CB<1>
  VSS43  = GND
  DQ0_B  = M_D_CPU0_SB_DQ<0>
  VSS44  = GND
  DQ1_B  = M_D_CPU0_SB_DQ<1>
  VSS45  = GND
  DQS0_B_T  = M_D_CPU0_SB_DQS_DP<0>
  DQS0_B_C  = M_D_CPU0_SB_DQS_DN<0>
  VSS46  = GND
  DQ4_B  = M_D_CPU0_SB_DQ<4>
  VSS47  = GND
  DQ5_B  = M_D_CPU0_SB_DQ<5>
  VSS48  = GND
  DQ8_B  = M_D_CPU0_SB_DQ<8>
  VSS49  = GND
  DQ9_B  = M_D_CPU0_SB_DQ<9>
  VSS50  = GND
  DQS1_B_T  = M_D_CPU0_SB_DQS_DP<1>
  DQS1_B_C  = M_D_CPU0_SB_DQS_DN<1>
  VSS51  = GND
  DQ12_B  = M_D_CPU0_SB_DQ<12>
  VSS52  = GND
  DQ13_B  = M_D_CPU0_SB_DQ<13>
  VSS53  = GND
  DQ16_B  = M_D_CPU0_SB_DQ<16>
  VSS54  = GND
  DQ17_B  = M_D_CPU0_SB_DQ<17>
  VSS55  = GND
  DQS2_B_T  = M_D_CPU0_SB_DQS_DP<2>
  DQS2_B_C  = M_D_CPU0_SB_DQS_DN<2>
  VSS56  = GND
  DQ20_B  = M_D_CPU0_SB_DQ<20>
  VSS57  = GND
  DQ21_B  = M_D_CPU0_SB_DQ<21>
  VSS58  = GND
  DQ24_B  = M_D_CPU0_SB_DQ<24>
  VSS59  = GND
  DQ25_B  = M_D_CPU0_SB_DQ<25>
  VSS60  = GND
  DQS3_B_T  = M_D_CPU0_SB_DQS_DP<3>
  DQS3_B_C  = M_D_CPU0_SB_DQS_DN<3>
  VSS61  = GND
  DQ28_B  = M_D_CPU0_SB_DQ<28>
  VSS62  = GND
  DQ29_B  = M_D_CPU0_SB_DQ<29>
  VSS63  = GND
  RFU1  = TP_CHD_CPU0_DIMM2_FRU_1
  VIN_BULK1  = P12V_S3_AUX_CPU0_NVDIMM
  VIN_BULK2  = P12V_S3_AUX_CPU0_NVDIMM
  \pwr_good||fail_n\  = PWRGD_CHD_CPU0_DIMM2
  HSA  = PD_CHD_CPU0_DIMM2_SAA
  RFU2  = TP_CHD_CPU0_DIMM2_FRU_2
  RFU3  = TP_CHD_CPU0_DIMM2_FRU_3
  VSS64  = GND
  DQ2_A  = M_D_CPU0_SA_DQ<2>
  VSS65  = GND
  DQ3_A  = M_D_CPU0_SA_DQ<3>
  VSS66  = GND
  \dqs5_a_c||tdqs5_a_c||dqs5_a_t||tdqs5_a_t\  = M_D_CPU0_SA_DQS_DN<5>
  \dqs5_a_t||tdqs5_a_t\  = M_D_CPU0_SA_DQS_DP<5>
  VSS67  = GND
  DQ6_A  = M_D_CPU0_SA_DQ<6>
  VSS68  = GND
  DQ7_A  = M_D_CPU0_SA_DQ<7>
  VSS69  = GND
  DQ10_A  = M_D_CPU0_SA_DQ<10>
  VSS70  = GND
  DQ11_A  = M_D_CPU0_SA_DQ<11>
  VSS71  = GND
  \dqs6_a_c||tdqs6_a_c||dqs6_a_t||tdqs6_a_t\  = M_D_CPU0_SA_DQS_DN<6>
  \dqs6_a_t||tdqs6_a_t\  = M_D_CPU0_SA_DQS_DP<6>
  VSS72  = GND
  DQ14_A  = M_D_CPU0_SA_DQ<14>
  VSS73  = GND
  DQ15_A  = M_D_CPU0_SA_DQ<15>
  VSS74  = GND
  DQ18_A  = M_D_CPU0_SA_DQ<18>
  VSS75  = GND
  DQ19_A  = M_D_CPU0_SA_DQ<19>
  VSS76  = GND
  \dqs7_a_c||tdqs7_a_c\  = M_D_CPU0_SA_DQS_DN<7>
  \dqs7_a_t||tdqs7_a_t\  = M_D_CPU0_SA_DQS_DP<7>
  VSS77  = GND
  DQ22_A  = M_D_CPU0_SA_DQ<22>
  VSS78  = GND
  DQ23_A  = M_D_CPU0_SA_DQ<23>
  VSS79  = GND
  DQ26_A  = M_D_CPU0_SA_DQ<26>
  VSS80  = GND
  DQ27_A  = M_D_CPU0_SA_DQ<27>
  VSS81  = GND
  \dqs8_a_c||tdqs8_a_c\  = M_D_CPU0_SA_DQS_DN<8>
  \dqs8_a_t||tdqs8_a_t\  = M_D_CPU0_SA_DQS_DP<8>
  VSS82  = GND
  DQ30_A  = M_D_CPU0_SA_DQ<30>
  VSS83  = GND
  DQ31_A  = M_D_CPU0_SA_DQ<31>
  VSS84  = GND
  CB2_A  = M_D_CPU0_SA_CB<2>
  VSS85  = GND
  CB3_A  = M_D_CPU0_SA_CB<3>
  VSS86  = GND
  \dqs9_a_c||tdqs9_a_c\  = M_D_CPU0_SA_DQS_DN<9>
  \dqs9_a_t||tdqs9_a_t\  = M_D_CPU0_SA_DQS_DP<9>
  VSS87  = GND
  CB6_A  = M_D_CPU0_SA_CB<6>
  VSS88  = GND
  CB7_A  = M_D_CPU0_SA_CB<7>
  VSS89  = GND
  RESET_N  = RST_M_CD_CPU0_FPGA_N
  VSS90  = GND
  CS1_A_N  = M_D_CPU0_SA_CS_N<3>
  VSS91  = GND
  CA1_A  = M_D_CPU0_SA_CA<1>
  VSS92  = GND
  CA3_A  = M_D_CPU0_SA_CA<3>
  VSS93  = GND
  CA5_A  = M_D_CPU0_SA_CA<5>
  VSS94  = GND
  CK_T  = M_D_CPU0_CLK_DP<1>
  CK_C  = M_D_CPU0_CLK_DN<1>
  VSS95  = GND
  RFU4  = TP_CHD_CPU0_DIMM2_FRU_4
  CA1_B  = M_D_CPU0_SB_CA<1>
  VSS96  = GND
  CA3_B  = M_D_CPU0_SB_CA<3>
  VSS97  = GND
  CA5_B  = M_D_CPU0_SB_CA<5>
  VSS98  = GND
  PAR_B  = M_D_CPU0_SB_PAR
  VSS99  = GND
  CS1_B_N  = M_D_CPU0_SB_CS_N<3>
  VSS100  = GND
  RFU5  = TP_CHD_CPU0_DIMM2_FRU_5
  RFU6  = TP_CHD_CPU0_DIMM2_FRU_6
  VSS101  = GND
  CB6_B  = M_D_CPU0_SB_CB<6>
  VSS102  = GND
  CB7_B  = M_D_CPU0_SB_CB<7>
  VSS103  = GND
  DQS4_B_C  = M_D_CPU0_SB_DQS_DN<4>
  DQS4_B_T  = M_D_CPU0_SB_DQS_DP<4>
  VSS104  = GND
  CB2_B  = M_D_CPU0_SB_CB<2>
  VSS105  = GND
  CB3_B  = M_D_CPU0_SB_CB<3>
  VSS106  = GND
  DQ2_B  = M_D_CPU0_SB_DQ<2>
  VSS107  = GND
  DQ3_B  = M_D_CPU0_SB_DQ<3>
  VSS108  = GND
  \dqs5_b_c||tdqs5_b_c\  = M_D_CPU0_SB_DQS_DN<5>
  \dqs5_b_t||tdqs5_b_t\  = M_D_CPU0_SB_DQS_DP<5>
  VSS109  = GND
  DQ6_B  = M_D_CPU0_SB_DQ<6>
  VSS110  = GND
  DQ7_B  = M_D_CPU0_SB_DQ<7>
  VSS111  = GND
  DQ10_B  = M_D_CPU0_SB_DQ<10>
  VSS112  = GND
  DQ11_B  = M_D_CPU0_SB_DQ<11>
  VSS113  = GND
  \dqs6_b_c||tdqs6_b_c\  = M_D_CPU0_SB_DQS_DN<6>
  \dqs6_b_t||tdqs6_b_t\  = M_D_CPU0_SB_DQS_DP<6>
  VSS114  = GND
  DQ14_B  = M_D_CPU0_SB_DQ<14>
  VSS115  = GND
  DQ15_B  = M_D_CPU0_SB_DQ<15>
  VSS116  = GND
  DQ18_B  = M_D_CPU0_SB_DQ<18>
  VSS117  = GND
  DQ19_B  = M_D_CPU0_SB_DQ<19>
  VSS118  = GND
  \dqs7_b_c||tdqs7_b_c\  = M_D_CPU0_SB_DQS_DN<7>
  \dqs7_b_t||tdqs7_b_t\  = M_D_CPU0_SB_DQS_DP<7>
  VSS119  = GND
  DQ22_B  = M_D_CPU0_SB_DQ<22>
  VSS120  = GND
  DQ23_B  = M_D_CPU0_SB_DQ<23>
  VSS121  = GND
  DQ26_B  = M_D_CPU0_SB_DQ<26>
  VSS122  = GND
  DQ27_B  = M_D_CPU0_SB_DQ<27>
  VSS123  = GND
  \dqs8_b_c||tdqs8_b_c\  = M_D_CPU0_SB_DQS_DN<8>
  \dqs8_b_t||tdqs8_b_t\  = M_D_CPU0_SB_DQS_DP<8>
  VSS124  = GND
  DQ30_B  = M_D_CPU0_SB_DQ<30>
  VSS125  = GND
  DQ31_B  = M_D_CPU0_SB_DQ<31>
  VSS126  = GND
  G1  = GND
  G2  = GND
  G3  = GND

(kicad_pcb
	(version 20260206)
	(generator "pcbnew")
	(generator_version "10.0")
	(general
		(thickness 1.6)
		(legacy_teardrops no)
	)
	(paper "A4")
	(title_block
		(title "03242023_DA0F0TMBIJ0_F0T_Motherboard_J_brd_V01_OCP.brd")
		(comment 1 "Grand Teton / footprint 652 of 6105 (J8), pads 46-91 of 291")
	)
	(layers
		(0 "F.Cu" signal "TOP")
		(4 "In1.Cu" signal "GND")
		(6 "In2.Cu" signal "IN1")
		(8 "In3.Cu" signal "GND1")
		(10 "In4.Cu" signal "IN2")
		(12 "In5.Cu" signal "GND2")
		(14 "In6.Cu" signal "IN3")
		(16 "In7.Cu" signal "GND3")
		(18 "In8.Cu" signal "VCC")
		(20 "In9.Cu" signal "VCC1")
		(22 "In10.Cu" signal "GND4")
		(24 "In11.Cu" signal "IN4")
		(26 "In12.Cu" signal "GND5")
		(28 "In13.Cu" signal "IN5")
		(30 "In14.Cu" signal "GND6")
		(32 "In15.Cu" signal "IN6")
		(34 "In16.Cu" signal "GND7")
		(2 "B.Cu" signal "BOTTOM")
		(9 "F.Adhes" user "F.Adhesive")
		(11 "B.Adhes" user "B.Adhesive")
		(13 "F.Paste" user "Package Geometry/Pastemask Top")
		(15 "B.Paste" user "Package Geometry/Pastemask Bottom")
		(5 "F.SilkS" user "Ref Des/Silkscreen Top")
		(7 "B.SilkS" user "Ref Des/Silkscreen Bottom")
		(1 "F.Mask" user "Board Geometry/Soldermask Top")
		(3 "B.Mask" user "Board Geometry/Soldermask Bottom")
		(17 "Dwgs.User" user "User.Drawings")
		(19 "Cmts.User" user "User.Comments")
		(21 "Eco1.User" user "User.Eco1")
		(23 "Eco2.User" user "User.Eco2")
		(25 "Edge.Cuts" user "Board Geometry/Outline")
		(27 "Margin" user)
		(31 "F.CrtYd" user "Package Geometry/Place Bound Top")
		(29 "B.CrtYd" user "Package Geometry/Place Bound Bottom")
		(35 "F.Fab" user "Ref Des/Assembly Top")
		(33 "B.Fab" user "Ref Des/Assembly Bottom")
	)
	(footprint ""
		(layer "F.Cu")
		(at 265.674348 -258.091686)
		(property "Reference" "J8"
			(at -3.683 -81.702148 0)
			(unlocked yes)
			(layer "F.SilkS")
			(effects
				(font
					(size 0.7874 0.5842)
					(thickness 0.1524)
				)
				(justify left)
			)
		)
		(property "Value" ""
			(at 0 0 0)
			(layer "F.Fab")
			(effects
				(font
					(size 1.27 1.27)
				)
			)
		)
		(duplicate_pad_numbers_are_jumpers no)
		(pad "46" smd rect
			(at -2.050034 -25.07488 270)
			(size 0.519938 1.4986)
			(layers "F.Cu" "F.Mask" "F.Paste")
			(net "GND")
		)
		(pad "47" smd rect
			(at -2.050034 -24.224996 270)
			(size 0.519938 1.4986)
			(layers "F.Cu" "F.Mask" "F.Paste")
			(net "M_D_CPU0_SA_DQ<28>")
		)
		(pad "48" smd rect
			(at -2.050034 -23.375112 270)
			(size 0.519938 1.4986)
			(layers "F.Cu" "F.Mask" "F.Paste")
			(net "GND")
		)
		(pad "49" smd rect
			(at -2.050034 -22.524974 270)
			(size 0.519938 1.4986)
			(layers "F.Cu" "F.Mask" "F.Paste")
			(net "M_D_CPU0_SA_DQ<29>")
		)
		(pad "50" smd rect
			(at -2.050034 -21.67509 270)
			(size 0.519938 1.4986)
			(layers "F.Cu" "F.Mask" "F.Paste")
			(net "GND")
		)
		(pad "51" smd rect
			(at -2.050034 -20.824952 270)
			(size 0.519938 1.4986)
			(layers "F.Cu" "F.Mask" "F.Paste")
			(net "M_D_CPU0_SA_CB<0>")
		)
		(pad "52" smd rect
			(at -2.050034 -19.975068 270)
			(size 0.519938 1.4986)
			(layers "F.Cu" "F.Mask" "F.Paste")
			(net "GND")
		)
		(pad "53" smd rect
			(at -2.050034 -19.12493 270)
			(size 0.519938 1.4986)
			(layers "F.Cu" "F.Mask" "F.Paste")
			(net "M_D_CPU0_SA_CB<1>")
		)
		(pad "54" smd rect
			(at -2.050034 -18.275046 270)
			(size 0.519938 1.4986)
			(layers "F.Cu" "F.Mask" "F.Paste")
			(net "GND")
		)
		(pad "55" smd rect
			(at -2.050034 -17.424908 270)
			(size 0.519938 1.4986)
			(layers "F.Cu" "F.Mask" "F.Paste")
			(net "M_D_CPU0_SA_DQS_DP<4>")
		)
		(pad "56" smd rect
			(at -2.050034 -16.575024 270)
			(size 0.519938 1.4986)
			(layers "F.Cu" "F.Mask" "F.Paste")
			(net "M_D_CPU0_SA_DQS_DN<4>")
		)
		(pad "57" smd rect
			(at -2.050034 -15.724886 270)
			(size 0.519938 1.4986)
			(layers "F.Cu" "F.Mask" "F.Paste")
			(net "GND")
		)
		(pad "58" smd rect
			(at -2.050034 -14.875002 270)
			(size 0.519938 1.4986)
			(layers "F.Cu" "F.Mask" "F.Paste")
			(net "M_D_CPU0_SA_CB<4>")
		)
		(pad "59" smd rect
			(at -2.050034 -14.025118 270)
			(size 0.519938 1.4986)
			(layers "F.Cu" "F.Mask" "F.Paste")
			(net "GND")
		)
		(pad "60" smd rect
			(at -2.050034 -13.17498 270)
			(size 0.519938 1.4986)
			(layers "F.Cu" "F.Mask" "F.Paste")
			(net "M_D_CPU0_SA_CB<5>")
		)
		(pad "61" smd rect
			(at -2.050034 -12.325096 270)
			(size 0.519938 1.4986)
			(layers "F.Cu" "F.Mask" "F.Paste")
			(net "GND")
		)
		(pad "62" smd rect
			(at -2.050034 -11.474958 270)
			(size 0.519938 1.4986)
			(layers "F.Cu" "F.Mask" "F.Paste")
			(net "M_D_CPU0_ALERT_N")
		)
		(pad "63" smd rect
			(at -2.050034 -10.625074 270)
			(size 0.519938 1.4986)
			(layers "F.Cu" "F.Mask" "F.Paste")
			(net "GND")
		)
		(pad "64" smd rect
			(at -2.050034 -9.774936 270)
			(size 0.519938 1.4986)
			(layers "F.Cu" "F.Mask" "F.Paste")
			(net "M_D_CPU0_SA_CS_N<2>")
		)
		(pad "65" smd rect
			(at -2.050034 -8.925052 270)
			(size 0.519938 1.4986)
			(layers "F.Cu" "F.Mask" "F.Paste")
			(net "GND")
		)
		(pad "66" smd rect
			(at -2.050034 -8.074914 270)
			(size 0.519938 1.4986)
			(layers "F.Cu" "F.Mask" "F.Paste")
			(net "M_D_CPU0_SA_CA<0>")
		)
		(pad "67" smd rect
			(at -2.050034 -7.22503 270)
			(size 0.519938 1.4986)
			(layers "F.Cu" "F.Mask" "F.Paste")
			(net "GND")
		)
		(pad "68" smd rect
			(at -2.050034 -6.374892 270)
			(size 0.519938 1.4986)
			(layers "F.Cu" "F.Mask" "F.Paste")
			(net "M_D_CPU0_SA_CA<2>")
		)
		(pad "69" smd rect
			(at -2.050034 -5.525008 270)
			(size 0.519938 1.4986)
			(layers "F.Cu" "F.Mask" "F.Paste")
			(net "GND")
		)
		(pad "70" smd rect
			(at -2.050034 -4.675124 270)
			(size 0.519938 1.4986)
			(layers "F.Cu" "F.Mask" "F.Paste")
			(net "M_D_CPU0_SA_CA<4>")
		)
		(pad "71" smd rect
			(at -2.050034 -3.824986 270)
			(size 0.519938 1.4986)
			(layers "F.Cu" "F.Mask" "F.Paste")
			(net "GND")
		)
		(pad "72" smd rect
			(at -2.050034 -2.975102 270)
			(size 0.519938 1.4986)
			(layers "F.Cu" "F.Mask" "F.Paste")
			(net "M_D_CPU0_SA_CA<6>")
		)
		(pad "73" smd rect
			(at -2.050034 -2.124964 270)
			(size 0.519938 1.4986)
			(layers "F.Cu" "F.Mask" "F.Paste")
			(net "GND")
		)
		(pad "74" smd rect
			(at -2.050034 -1.27508 270)
			(size 0.519938 1.4986)
			(layers "F.Cu" "F.Mask" "F.Paste")
			(net "M_D_CPU0_SA_PAR")
		)
		(pad "75" smd rect
			(at -2.050034 -0.424942 270)
			(size 0.519938 1.4986)
			(layers "F.Cu" "F.Mask" "F.Paste")
			(net "GND")
		)
		(pad "76" smd rect
			(at -2.050034 5.525008 270)
			(size 0.519938 1.4986)
			(layers "F.Cu" "F.Mask" "F.Paste")
			(net "M_D_CPU0_SB_CA<0>")
		)
		(pad "77" smd rect
			(at -2.050034 6.374892 270)
			(size 0.519938 1.4986)
			(layers "F.Cu" "F.Mask" "F.Paste")
			(net "GND")
		)
		(pad "78" smd rect
			(at -2.050034 7.22503 270)
			(size 0.519938 1.4986)
			(layers "F.Cu" "F.Mask" "F.Paste")
			(net "M_D_CPU0_SB_CA<2>")
		)
		(pad "79" smd rect
			(at -2.050034 8.074914 270)
			(size 0.519938 1.4986)
			(layers "F.Cu" "F.Mask" "F.Paste")
			(net "GND")
		)
		(pad "80" smd rect
			(at -2.050034 8.925052 270)
			(size 0.519938 1.4986)
			(layers "F.Cu" "F.Mask" "F.Paste")
			(net "M_D_CPU0_SB_CA<4>")
		)
		(pad "81" smd rect
			(at -2.050034 9.774936 270)
			(size 0.519938 1.4986)
			(layers "F.Cu" "F.Mask" "F.Paste")
			(net "GND")
		)
		(pad "82" smd rect
			(at -2.050034 10.625074 270)
			(size 0.519938 1.4986)
			(layers "F.Cu" "F.Mask" "F.Paste")
			(net "M_D_CPU0_SB_CA<6>")
		)
		(pad "83" smd rect
			(at -2.050034 11.474958 270)
			(size 0.519938 1.4986)
			(layers "F.Cu" "F.Mask" "F.Paste")
			(net "GND")
		)
		(pad "84" smd rect
			(at -2.050034 12.325096 270)
			(size 0.519938 1.4986)
			(layers "F.Cu" "F.Mask" "F.Paste")
			(net "M_D_CPU0_SB_CS_N<2>")
		)
		(pad "85" smd rect
			(at -2.050034 13.17498 270)
			(size 0.519938 1.4986)
			(layers "F.Cu" "F.Mask" "F.Paste")
			(net "GND")
		)
		(pad "86" smd rect
			(at -2.050034 14.025118 270)
			(size 0.519938 1.4986)
			(layers "F.Cu" "F.Mask" "F.Paste")
			(net "M_D_CPU0_SA_RSP<1>")
		)
		(pad "87" smd rect
			(at -2.050034 14.875002 270)
			(size 0.519938 1.4986)
			(layers "F.Cu" "F.Mask" "F.Paste")
			(net "M_D_CPU0_SB_RSP<1>")
		)
		(pad "88" smd rect
			(at -2.050034 15.724886 270)
			(size 0.519938 1.4986)
			(layers "F.Cu" "F.Mask" "F.Paste")
			(net "GND")
		)
		(pad "89" smd rect
			(at -2.050034 16.575024 270)
			(size 0.519938 1.4986)
			(layers "F.Cu" "F.Mask" "F.Paste")
			(net "M_D_CPU0_SB_CB<4>")
		)
		(pad "90" smd rect
			(at -2.050034 17.424908 270)
			(size 0.519938 1.4986)
			(layers "F.Cu" "F.Mask" "F.Paste")
			(net "GND")
		)
		(pad "91" smd rect
			(at -2.050034 18.275046 270)
			(size 0.519938 1.4986)
			(layers "F.Cu" "F.Mask" "F.Paste")
			(net "M_D_CPU0_SB_CB<5>")
		)
	)
)
